(kicad_pcb
	(version 20260206)
	(generator "pcbnew")
	(generator_version "10.0")
	(general
		(thickness 1.6)
		(legacy_teardrops no)
	)
	(paper "A4")
	(title_block
		(title "04192023_DAF0TMB3IC0_F0TG_MB_C_brd_V02_OCP.brd")
		(comment 1 "Grand Teton / footprints 4316-4321 of 8354")
	)
	(layers
		(0 "F.Cu" signal "TOP")
		(4 "In1.Cu" signal "GND")
		(6 "In2.Cu" signal "IN1")
		(8 "In3.Cu" signal "GND1")
		(10 "In4.Cu" signal "IN2")
		(12 "In5.Cu" signal "GND2")
		(14 "In6.Cu" signal "IN3")
		(16 "In7.Cu" signal "GND3")
		(18 "In8.Cu" signal "VCC")
		(20 "In9.Cu" signal "VCC1")
		(22 "In10.Cu" signal "GND4")
		(24 "In11.Cu" signal "IN4")
		(26 "In12.Cu" signal "GND5")
		(28 "In13.Cu" signal "IN5")
		(30 "In14.Cu" signal "GND6")
		(32 "In15.Cu" signal "IN6")
		(34 "In16.Cu" signal "GND7")
		(2 "B.Cu" signal "BOTTOM")
		(9 "F.Adhes" user "F.Adhesive")
		(11 "B.Adhes" user "B.Adhesive")
		(13 "F.Paste" user "Package Geometry/Pastemask Top")
		(15 "B.Paste" user "Package Geometry/Pastemask Bottom")
		(5 "F.SilkS" user "Ref Des/Silkscreen Top")
		(7 "B.SilkS" user "Ref Des/Silkscreen Bottom")
		(1 "F.Mask" user "Board Geometry/Soldermask Top")
		(3 "B.Mask" user "Board Geometry/Soldermask Bottom")
		(17 "Dwgs.User" user "User.Drawings")
		(19 "Cmts.User" user "User.Comments")
		(21 "Eco1.User" user "User.Eco1")
		(23 "Eco2.User" user "User.Eco2")
		(25 "Edge.Cuts" user "Board Geometry/Outline")
		(27 "Margin" user)
		(31 "F.CrtYd" user "Package Geometry/Place Bound Top")
		(29 "B.CrtYd" user "Package Geometry/Place Bound Bottom")
		(35 "F.Fab" user "Ref Des/Assembly Top")
		(33 "B.Fab" user "Ref Des/Assembly Bottom")
	)
	(footprint ""
		(layer "F.Cu")
		(at 49.38268 -36.820348)
		(property "Reference" "R3207"
			(at 0 0 0)
			(layer "F.SilkS")
			(hide yes)
			(effects
				(font
					(size 1.27 1.27)
				)
			)
		)
		(property "Value" ""
			(at 0 0 0)
			(layer "F.Fab")
			(effects
				(font
					(size 1.27 1.27)
				)
			)
		)
		(duplicate_pad_numbers_are_jumpers no)
		(fp_line
			(start -0.7874 -0.4064)
			(end 0.7874 -0.4064)
			(stroke
				(width 0.1524)
				(type default)
			)
			(layer "F.SilkS")
		)
		(fp_line
			(start -0.7874 0.4064)
			(end -0.7874 -0.4064)
			(stroke
				(width 0.1524)
				(type default)
			)
			(layer "F.SilkS")
		)
		(fp_line
			(start 0.7874 -0.4064)
			(end 0.7874 0.4064)
			(stroke
				(width 0.1524)
				(type default)
			)
			(layer "F.SilkS")
		)
		(fp_line
			(start 0.7874 0.4064)
			(end -0.7874 0.4064)
			(stroke
				(width 0.1524)
				(type default)
			)
			(layer "F.SilkS")
		)
		(fp_line
			(start -0.67945 -0.305054)
			(end -0.12065 -0.305054)
			(stroke
				(width 0.1)
				(type default)
			)
			(layer "F.Fab")
		)
		(fp_line
			(start -0.67945 0.3048)
			(end -0.67945 -0.305054)
			(stroke
				(width 0.1)
				(type default)
			)
			(layer "F.Fab")
		)
		(fp_line
			(start -0.12065 -0.305054)
			(end -0.12065 -0.2794)
			(stroke
				(width 0.1)
				(type default)
			)
			(layer "F.Fab")
		)
		(fp_line
			(start -0.12065 -0.2794)
			(end 0.12065 -0.2794)
			(stroke
				(width 0.1)
				(type default)
			)
			(layer "F.Fab")
		)
		(fp_line
			(start -0.12065 0.2794)
			(end -0.12065 0.3048)
			(stroke
				(width 0.1)
				(type default)
			)
			(layer "F.Fab")
		)
		(fp_line
			(start -0.12065 0.3048)
			(end -0.67945 0.3048)
			(stroke
				(width 0.1)
				(type default)
			)
			(layer "F.Fab")
		)
		(fp_line
			(start 0.120396 0.2794)
			(end -0.12065 0.2794)
			(stroke
				(width 0.1)
				(type default)
			)
			(layer "F.Fab")
		)
		(fp_line
			(start 0.120396 0.3048)
			(end 0.120396 0.2794)
			(stroke
				(width 0.1)
				(type default)
			)
			(layer "F.Fab")
		)
		(fp_line
			(start 0.12065 -0.3048)
			(end 0.67945 -0.3048)
			(stroke
				(width 0.1)
				(type default)
			)
			(layer "F.Fab")
		)
		(fp_line
			(start 0.12065 -0.2794)
			(end 0.12065 -0.3048)
			(stroke
				(width 0.1)
				(type default)
			)
			(layer "F.Fab")
		)
		(fp_line
			(start 0.67945 -0.3048)
			(end 0.67945 0.3048)
			(stroke
				(width 0.1)
				(type default)
			)
			(layer "F.Fab")
		)
		(fp_line
			(start 0.67945 0.3048)
			(end 0.120396 0.3048)
			(stroke
				(width 0.1)
				(type default)
			)
			(layer "F.Fab")
		)
		(pad "1" smd circle
			(at -0.40005 0)
			(size 0 0)
			(layers "F.Cu" "F.Mask" "F.Paste")
			(net "FB_BMC_ISOLATE1")
		)
		(pad "2" smd circle
			(at 0.40005 0)
			(size 0 0)
			(layers "F.Cu" "F.Mask" "F.Paste")
			(net "GND")
		)
	)
	(footprint ""
		(layer "F.Cu")
		(at 423.23766 -365.812578 90)
		(property "Reference" "PC4"
			(at 0 0 90)
			(layer "F.SilkS")
			(hide yes)
			(effects
				(font
					(size 1.27 1.27)
				)
			)
		)
		(property "Value" ""
			(at 0 0 90)
			(layer "F.Fab")
			(effects
				(font
					(size 1.27 1.27)
				)
			)
		)
		(duplicate_pad_numbers_are_jumpers no)
		(fp_line
			(start 0.7874 -0.4064)
			(end 0.7874 0.4064)
			(stroke
				(width 0.1524)
				(type default)
			)
			(layer "F.SilkS")
		)
		(fp_line
			(start -0.7874 -0.4064)
			(end 0.7874 -0.4064)
			(stroke
				(width 0.1524)
				(type default)
			)
			(layer "F.SilkS")
		)
		(fp_line
			(start 0.7874 0.4064)
			(end -0.7874 0.4064)
			(stroke
				(width 0.1524)
				(type default)
			)
			(layer "F.SilkS")
		)
		(fp_line
			(start -0.7874 0.4064)
			(end -0.7874 -0.4064)
			(stroke
				(width 0.1524)
				(type default)
			)
			(layer "F.SilkS")
		)
		(fp_line
			(start -0.12065 -0.305054)
			(end -0.12065 -0.2794)
			(stroke
				(width 0.1)
				(type default)
			)
			(layer "F.Fab")
		)
		(fp_line
			(start -0.67945 -0.305054)
			(end -0.12065 -0.305054)
			(stroke
				(width 0.1)
				(type default)
			)
			(layer "F.Fab")
		)
		(fp_line
			(start 0.67945 -0.3048)
			(end 0.67945 0.3048)
			(stroke
				(width 0.1)
				(type default)
			)
			(layer "F.Fab")
		)
		(fp_line
			(start 0.12065 -0.3048)
			(end 0.67945 -0.3048)
			(stroke
				(width 0.1)
				(type default)
			)
			(layer "F.Fab")
		)
		(fp_line
			(start 0.12065 -0.2794)
			(end 0.12065 -0.3048)
			(stroke
				(width 0.1)
				(type default)
			)
			(layer "F.Fab")
		)
		(fp_line
			(start -0.12065 -0.2794)
			(end 0.12065 -0.2794)
			(stroke
				(width 0.1)
				(type default)
			)
			(layer "F.Fab")
		)
		(fp_line
			(start 0.120396 0.2794)
			(end -0.12065 0.2794)
			(stroke
				(width 0.1)
				(type default)
			)
			(layer "F.Fab")
		)
		(fp_line
			(start -0.12065 0.2794)
			(end -0.12065 0.3048)
			(stroke
				(width 0.1)
				(type default)
			)
			(layer "F.Fab")
		)
		(fp_line
			(start 0.67945 0.3048)
			(end 0.120396 0.3048)
			(stroke
				(width 0.1)
				(type default)
			)
			(layer "F.Fab")
		)
		(fp_line
			(start 0.120396 0.3048)
			(end 0.120396 0.2794)
			(stroke
				(width 0.1)
				(type default)
			)
			(layer "F.Fab")
		)
		(fp_line
			(start -0.12065 0.3048)
			(end -0.67945 0.3048)
			(stroke
				(width 0.1)
				(type default)
			)
			(layer "F.Fab")
		)
		(fp_line
			(start -0.67945 0.3048)
			(end -0.67945 -0.305054)
			(stroke
				(width 0.1)
				(type default)
			)
			(layer "F.Fab")
		)
		(pad "1" smd circle
			(at -0.40005 0 90)
			(size 0 0)
			(layers "F.Cu" "F.Mask" "F.Paste")
			(net "PVDD11_S3_P0_VCC")
		)
		(pad "2" smd circle
			(at 0.40005 0 90)
			(size 0 0)
			(layers "F.Cu" "F.Mask" "F.Paste")
			(net "GND")
		)
	)
	(footprint ""
		(layer "F.Cu")
		(at 425.05249 -57.047638)
		(property "Reference" "U124"
			(at -2.032 -2.377948 0)
			(unlocked yes)
			(layer "F.SilkS")
			(effects
				(font
					(size 0.7874 0.5842)
					(thickness 0.1524)
				)
				(justify left)
			)
		)
		(property "Value" ""
			(at 0 0 0)
			(layer "F.Fab")
			(effects
				(font
					(size 1.27 1.27)
				)
			)
		)
		(duplicate_pad_numbers_are_jumpers no)
		(fp_line
			(start -2.0574 -1.651)
			(end -0.381 -1.651)
			(stroke
				(width 0.1524)
				(type default)
			)
			(layer "F.SilkS")
		)
		(fp_line
			(start -2.0574 1.651)
			(end -2.0574 -1.651)
			(stroke
				(width 0.1524)
				(type default)
			)
			(layer "F.SilkS")
		)
		(fp_line
			(start -0.381 -1.651)
			(end 0 -1.016)
			(stroke
				(width 0.1524)
				(type default)
			)
			(layer "F.SilkS")
		)
		(fp_line
			(start 0 -1.016)
			(end 0.381 -1.651)
			(stroke
				(width 0.1524)
				(type default)
			)
			(layer "F.SilkS")
		)
		(fp_line
			(start 0.381 -1.651)
			(end 2.0574 -1.651)
			(stroke
				(width 0.1524)
				(type default)
			)
			(layer "F.SilkS")
		)
		(fp_line
			(start 2.0574 -1.651)
			(end 2.0574 1.651)
			(stroke
				(width 0.1524)
				(type default)
			)
			(layer "F.SilkS")
		)
		(fp_line
			(start 2.0574 1.651)
			(end -2.0574 1.651)
			(stroke
				(width 0.1524)
				(type default)
			)
			(layer "F.SilkS")
		)
		(fp_poly
			(pts
				(xy -2.511806 -1.813052) (xy -3.113278 -1.994662) (xy -2.671318 -2.436622)
			)
			(stroke
				(width 0)
				(type default)
			)
			(fill yes)
			(layer "F.SilkS")
		)
		(fp_line
			(start -1.599946 -1.199896)
			(end -0.899922 -1.199896)
			(stroke
				(width 0.1)
				(type default)
			)
			(layer "F.Fab")
		)
		(fp_line
			(start -1.599946 1.199896)
			(end -1.599946 -1.199896)
			(stroke
				(width 0.1)
				(type default)
			)
			(layer "F.Fab")
		)
		(fp_line
			(start -0.899922 -1.549908)
			(end 0.899922 -1.549908)
			(stroke
				(width 0.1)
				(type default)
			)
			(layer "F.Fab")
		)
		(fp_line
			(start -0.899922 -1.199896)
			(end -0.899922 -1.549908)
			(stroke
				(width 0.1)
				(type default)
			)
			(layer "F.Fab")
		)
		(fp_line
			(start -0.899922 1.199896)
			(end -1.599946 1.199896)
			(stroke
				(width 0.1)
				(type default)
			)
			(layer "F.Fab")
		)
		(fp_line
			(start -0.899922 1.549908)
			(end -0.899922 1.199896)
			(stroke
				(width 0.1)
				(type default)
			)
			(layer "F.Fab")
		)
		(fp_line
			(start 0.899922 -1.549908)
			(end 0.899922 -1.199896)
			(stroke
				(width 0.1)
				(type default)
			)
			(layer "F.Fab")
		)
		(fp_line
			(start 0.899922 -1.199896)
			(end 1.599946 -1.199896)
			(stroke
				(width 0.1)
				(type default)
			)
			(layer "F.Fab")
		)
		(fp_line
			(start 0.899922 1.199896)
			(end 0.899922 1.549908)
			(stroke
				(width 0.1)
				(type default)
			)
			(layer "F.Fab")
		)
		(fp_line
			(start 0.899922 1.549908)
			(end -0.899922 1.549908)
			(stroke
				(width 0.1)
				(type default)
			)
			(layer "F.Fab")
		)
		(fp_line
			(start 1.599946 -1.199896)
			(end 1.599946 1.199896)
			(stroke
				(width 0.1)
				(type default)
			)
			(layer "F.Fab")
		)
		(fp_line
			(start 1.599946 1.199896)
			(end 0.899922 1.199896)
			(stroke
				(width 0.1)
				(type default)
			)
			(layer "F.Fab")
		)
		(fp_poly
			(pts
				(xy -2.71272 -0.719328) (xy -2.71272 -1.344168) (xy -2.159 -1.016)
			)
			(stroke
				(width 0)
				(type default)
			)
			(fill yes)
			(layer "F.Fab")
		)
		(pad "1" smd rect
			(at -1.225042 -0.94996 270)
			(size 0.5588 1.3462)
			(layers "F.Cu" "F.Mask" "F.Paste")
			(net "Net_10728")
		)
		(pad "2" smd rect
			(at -1.225042 0 270)
			(size 0.5588 1.3462)
			(layers "F.Cu" "F.Mask" "F.Paste")
			(net "FM_JTAG_BMC_R_OE")
		)
		(pad "3" smd rect
			(at -1.225042 0.94996 270)
			(size 0.5588 1.3462)
			(layers "F.Cu" "F.Mask" "F.Paste")
			(net "GND")
		)
		(pad "4" smd rect
			(at 1.225042 0.94996 270)
			(size 0.5588 1.3462)
			(layers "F.Cu" "F.Mask" "F.Paste")
			(net "JTAG_BMC_OE")
		)
		(pad "5" smd rect
			(at 1.225042 -0.94996 270)
			(size 0.5588 1.3462)
			(layers "F.Cu" "F.Mask" "F.Paste")
			(net "U124_VCC")
		)
	)
	(footprint ""
		(layer "F.Cu")
		(at 115.315238 -41.17975 -90)
		(property "Reference" "R6283"
			(at 0 0 270)
			(layer "F.SilkS")
			(hide yes)
			(effects
				(font
					(size 1.27 1.27)
				)
			)
		)
		(property "Value" ""
			(at 0 0 270)
			(layer "F.Fab")
			(effects
				(font
					(size 1.27 1.27)
				)
			)
		)
		(duplicate_pad_numbers_are_jumpers no)
		(fp_line
			(start -0.7874 0.4064)
			(end -0.7874 -0.4064)
			(stroke
				(width 0.1524)
				(type default)
			)
			(layer "F.SilkS")
		)
		(fp_line
			(start 0.7874 0.4064)
			(end -0.7874 0.4064)
			(stroke
				(width 0.1524)
				(type default)
			)
			(layer "F.SilkS")
		)
		(fp_line
			(start -0.7874 -0.4064)
			(end 0.7874 -0.4064)
			(stroke
				(width 0.1524)
				(type default)
			)
			(layer "F.SilkS")
		)
		(fp_line
			(start 0.7874 -0.4064)
			(end 0.7874 0.4064)
			(stroke
				(width 0.1524)
				(type default)
			)
			(layer "F.SilkS")
		)
		(fp_line
			(start -0.67945 0.3048)
			(end -0.67945 -0.305054)
			(stroke
				(width 0.1)
				(type default)
			)
			(layer "F.Fab")
		)
		(fp_line
			(start -0.12065 0.3048)
			(end -0.67945 0.3048)
			(stroke
				(width 0.1)
				(type default)
			)
			(layer "F.Fab")
		)
		(fp_line
			(start 0.120396 0.3048)
			(end 0.120396 0.2794)
			(stroke
				(width 0.1)
				(type default)
			)
			(layer "F.Fab")
		)
		(fp_line
			(start 0.67945 0.3048)
			(end 0.120396 0.3048)
			(stroke
				(width 0.1)
				(type default)
			)
			(layer "F.Fab")
		)
		(fp_line
			(start -0.12065 0.2794)
			(end -0.12065 0.3048)
			(stroke
				(width 0.1)
				(type default)
			)
			(layer "F.Fab")
		)
		(fp_line
			(start 0.120396 0.2794)
			(end -0.12065 0.2794)
			(stroke
				(width 0.1)
				(type default)
			)
			(layer "F.Fab")
		)
		(fp_line
			(start -0.12065 -0.2794)
			(end 0.12065 -0.2794)
			(stroke
				(width 0.1)
				(type default)
			)
			(layer "F.Fab")
		)
		(fp_line
			(start 0.12065 -0.2794)
			(end 0.12065 -0.3048)
			(stroke
				(width 0.1)
				(type default)
			)
			(layer "F.Fab")
		)
		(fp_line
			(start 0.12065 -0.3048)
			(end 0.67945 -0.3048)
			(stroke
				(width 0.1)
				(type default)
			)
			(layer "F.Fab")
		)
		(fp_line
			(start 0.67945 -0.3048)
			(end 0.67945 0.3048)
			(stroke
				(width 0.1)
				(type default)
			)
			(layer "F.Fab")
		)
		(fp_line
			(start -0.67945 -0.305054)
			(end -0.12065 -0.305054)
			(stroke
				(width 0.1)
				(type default)
			)
			(layer "F.Fab")
		)
		(fp_line
			(start -0.12065 -0.305054)
			(end -0.12065 -0.2794)
			(stroke
				(width 0.1)
				(type default)
			)
			(layer "F.Fab")
		)
		(pad "1" smd circle
			(at -0.40005 0 270)
			(size 0 0)
			(layers "F.Cu" "F.Mask" "F.Paste")
			(net "P3V3_AUX")
		)
		(pad "2" smd circle
			(at 0.40005 0 270)
			(size 0 0)
			(layers "F.Cu" "F.Mask" "F.Paste")
			(net "USB_HUB2_TI_FULLPWRMGMTZ_MRP_PROG_FUNC3")
		)
	)
	(footprint ""
		(layer "F.Cu")
		(at 157.677358 -352.229928)
		(property "Reference" "R8380"
			(at 0 0 0)
			(layer "F.SilkS")
			(hide yes)
			(effects
				(font
					(size 1.27 1.27)
				)
			)
		)
		(property "Value" ""
			(at 0 0 0)
			(layer "F.Fab")
			(effects
				(font
					(size 1.27 1.27)
				)
			)
		)
		(duplicate_pad_numbers_are_jumpers no)
		(fp_line
			(start -0.7874 -0.4064)
			(end 0.7874 -0.4064)
			(stroke
				(width 0.1524)
				(type default)
			)
			(layer "F.SilkS")
		)
		(fp_line
			(start -0.7874 0.4064)
			(end -0.7874 -0.4064)
			(stroke
				(width 0.1524)
				(type default)
			)
			(layer "F.SilkS")
		)
		(fp_line
			(start 0.7874 -0.4064)
			(end 0.7874 0.4064)
			(stroke
				(width 0.1524)
				(type default)
			)
			(layer "F.SilkS")
		)
		(fp_line
			(start 0.7874 0.4064)
			(end -0.7874 0.4064)
			(stroke
				(width 0.1524)
				(type default)
			)
			(layer "F.SilkS")
		)
		(fp_line
			(start -0.67945 -0.305054)
			(end -0.12065 -0.305054)
			(stroke
				(width 0.1)
				(type default)
			)
			(layer "F.Fab")
		)
		(fp_line
			(start -0.67945 0.3048)
			(end -0.67945 -0.305054)
			(stroke
				(width 0.1)
				(type default)
			)
			(layer "F.Fab")
		)
		(fp_line
			(start -0.12065 -0.305054)
			(end -0.12065 -0.2794)
			(stroke
				(width 0.1)
				(type default)
			)
			(layer "F.Fab")
		)
		(fp_line
			(start -0.12065 -0.2794)
			(end 0.12065 -0.2794)
			(stroke
				(width 0.1)
				(type default)
			)
			(layer "F.Fab")
		)
		(fp_line
			(start -0.12065 0.2794)
			(end -0.12065 0.3048)
			(stroke
				(width 0.1)
				(type default)
			)
			(layer "F.Fab")
		)
		(fp_line
			(start -0.12065 0.3048)
			(end -0.67945 0.3048)
			(stroke
				(width 0.1)
				(type default)
			)
			(layer "F.Fab")
		)
		(fp_line
			(start 0.120396 0.2794)
			(end -0.12065 0.2794)
			(stroke
				(width 0.1)
				(type default)
			)
			(layer "F.Fab")
		)
		(fp_line
			(start 0.120396 0.3048)
			(end 0.120396 0.2794)
			(stroke
				(width 0.1)
				(type default)
			)
			(layer "F.Fab")
		)
		(fp_line
			(start 0.12065 -0.3048)
			(end 0.67945 -0.3048)
			(stroke
				(width 0.1)
				(type default)
			)
			(layer "F.Fab")
		)
		(fp_line
			(start 0.12065 -0.2794)
			(end 0.12065 -0.3048)
			(stroke
				(width 0.1)
				(type default)
			)
			(layer "F.Fab")
		)
		(fp_line
			(start 0.67945 -0.3048)
			(end 0.67945 0.3048)
			(stroke
				(width 0.1)
				(type default)
			)
			(layer "F.Fab")
		)
		(fp_line
			(start 0.67945 0.3048)
			(end 0.120396 0.3048)
			(stroke
				(width 0.1)
				(type default)
			)
			(layer "F.Fab")
		)
		(pad "1" smd circle
			(at -0.40005 0)
			(size 0 0)
			(layers "F.Cu" "F.Mask" "F.Paste")
			(net "P3V3_AUX")
		)
		(pad "2" smd circle
			(at 0.40005 0)
			(size 0 0)
			(layers "F.Cu" "F.Mask" "F.Paste")
			(net "PWRGD_PVDD11_S3_P1_R")
		)
	)
	(footprint ""
		(layer "F.Cu")
		(at 111.76 -406.4508)
		(property "Reference" "R592"
			(at 0 0 0)
			(layer "F.SilkS")
			(hide yes)
			(effects
				(font
					(size 1.27 1.27)
				)
			)
		)
		(property "Value" ""
			(at 0 0 0)
			(layer "F.Fab")
			(effects
				(font
					(size 1.27 1.27)
				)
			)
		)
		(duplicate_pad_numbers_are_jumpers no)
		(fp_line
			(start -0.7874 -0.4064)
			(end 0.7874 -0.4064)
			(stroke
				(width 0.1524)
				(type default)
			)
			(layer "F.SilkS")
		)
		(fp_line
			(start -0.7874 0.4064)
			(end -0.7874 -0.4064)
			(stroke
				(width 0.1524)
				(type default)
			)
			(layer "F.SilkS")
		)
		(fp_line
			(start 0.7874 -0.4064)
			(end 0.7874 0.4064)
			(stroke
				(width 0.1524)
				(type default)
			)
			(layer "F.SilkS")
		)
		(fp_line
			(start 0.7874 0.4064)
			(end -0.7874 0.4064)
			(stroke
				(width 0.1524)
				(type default)
			)
			(layer "F.SilkS")
		)
		(fp_line
			(start -0.67945 -0.305054)
			(end -0.12065 -0.305054)
			(stroke
				(width 0.1)
				(type default)
			)
			(layer "F.Fab")
		)
		(fp_line
			(start -0.67945 0.3048)
			(end -0.67945 -0.305054)
			(stroke
				(width 0.1)
				(type default)
			)
			(layer "F.Fab")
		)
		(fp_line
			(start -0.12065 -0.305054)
			(end -0.12065 -0.2794)
			(stroke
				(width 0.1)
				(type default)
			)
			(layer "F.Fab")
		)
		(fp_line
			(start -0.12065 -0.2794)
			(end 0.12065 -0.2794)
			(stroke
				(width 0.1)
				(type default)
			)
			(layer "F.Fab")
		)
		(fp_line
			(start -0.12065 0.2794)
			(end -0.12065 0.3048)
			(stroke
				(width 0.1)
				(type default)
			)
			(layer "F.Fab")
		)
		(fp_line
			(start -0.12065 0.3048)
			(end -0.67945 0.3048)
			(stroke
				(width 0.1)
				(type default)
			)
			(layer "F.Fab")
		)
		(fp_line
			(start 0.120396 0.2794)
			(end -0.12065 0.2794)
			(stroke
				(width 0.1)
				(type default)
			)
			(layer "F.Fab")
		)
		(fp_line
			(start 0.120396 0.3048)
			(end 0.120396 0.2794)
			(stroke
				(width 0.1)
				(type default)
			)
			(layer "F.Fab")
		)
		(fp_line
			(start 0.12065 -0.3048)
			(end 0.67945 -0.3048)
			(stroke
				(width 0.1)
				(type default)
			)
			(layer "F.Fab")
		)
		(fp_line
			(start 0.12065 -0.2794)
			(end 0.12065 -0.3048)
			(stroke
				(width 0.1)
				(type default)
			)
			(layer "F.Fab")
		)
		(fp_line
			(start 0.67945 -0.3048)
			(end 0.67945 0.3048)
			(stroke
				(width 0.1)
				(type default)
			)
			(layer "F.Fab")
		)
		(fp_line
			(start 0.67945 0.3048)
			(end 0.120396 0.3048)
			(stroke
				(width 0.1)
				(type default)
			)
			(layer "F.Fab")
		)
		(pad "1" smd circle
			(at -0.40005 0)
			(size 0 0)
			(layers "F.Cu" "F.Mask" "F.Paste")
			(net "FM_9ZXL045_P1_2_OE_N")
		)
		(pad "2" smd circle
			(at 0.40005 0)
			(size 0 0)
			(layers "F.Cu" "F.Mask" "F.Paste")
			(net "GND")
		)
	)
)
